(kicad_pcb
	(version 20260206)
	(generator "pcbnew")
	(generator_version "10.0")
	(general
		(thickness 1.6)
		(legacy_teardrops no)
	)
	(paper "A4")
	(title_block
		(title "baseboard — 13948-1b.1110WZS1818.brd")
		(comment 1 "Honey Badger (Wiwynn) / footprints 1298-1305 of 2523")
	)
	(layers
		(0 "F.Cu" signal "TOP")
		(4 "In1.Cu" signal "L2GND")
		(6 "In2.Cu" signal "L3")
		(8 "In3.Cu" signal "L4VCC")
		(10 "In4.Cu" signal "L5VCC")
		(12 "In5.Cu" signal "L6")
		(14 "In6.Cu" signal "L7GND")
		(2 "B.Cu" signal "BOTTOM")
		(9 "F.Adhes" user "F.Adhesive")
		(11 "B.Adhes" user "B.Adhesive")
		(13 "F.Paste" user "Package Geometry/Pastemask Top")
		(15 "B.Paste" user "Package Geometry/Pastemask Bottom")
		(5 "F.SilkS" user "Ref Des/Silkscreen Top")
		(7 "B.SilkS" user "Ref Des/Silkscreen Bottom")
		(1 "F.Mask" user "Board Geometry/Soldermask Top")
		(3 "B.Mask" user "Board Geometry/Soldermask Bottom")
		(17 "Dwgs.User" user "User.Drawings")
		(19 "Cmts.User" user "User.Comments")
		(21 "Eco1.User" user "User.Eco1")
		(23 "Eco2.User" user "User.Eco2")
		(25 "Edge.Cuts" user "Board Geometry/Outline")
		(27 "Margin" user)
		(31 "F.CrtYd" user "Package Geometry/Place Bound Top")
		(29 "B.CrtYd" user "Package Geometry/Place Bound Bottom")
		(35 "F.Fab" user "Ref Des/Assembly Top")
		(33 "B.Fab" user "Ref Des/Assembly Bottom")
	)
	(footprint ""
		(layer "F.Cu")
		(at 152.247092 -108.233464 -90)
		(property "Reference" "SR831"
			(at 0 0 270)
			(layer "F.SilkS")
			(hide yes)
			(effects
				(font
					(size 1.27 1.27)
				)
			)
		)
		(property "Value" "D51R3F-2-GP"
			(at -0.0254 -2.5146 270)
			(unlocked yes)
			(layer "F.Fab")
			(hide yes)
			(effects
				(font
					(size 1.016 1.016)
					(thickness 0.1524)
				)
			)
		)
		(property "Device Type" "R603H22"
			(at -0.0254 -4.0386 270)
			(unlocked yes)
			(layer "F.Fab")
			(hide yes)
			(effects
				(font
					(size 1.016 1.016)
					(thickness 0.1524)
				)
			)
		)
		(duplicate_pad_numbers_are_jumpers no)
		(fp_line
			(start -0.4826 0)
			(end -0.2032 0)
			(stroke
				(width 0.2032)
				(type default)
			)
			(layer "F.SilkS")
		)
		(fp_line
			(start 0.2032 0)
			(end 0.4826 0)
			(stroke
				(width 0.2032)
				(type default)
			)
			(layer "F.SilkS")
		)
		(fp_rect
			(start -0.5842 1.3335)
			(end 0.5842 -1.3335)
			(stroke
				(width 0)
				(type default)
			)
			(fill no)
			(layer "F.CrtYd")
		)
		(fp_rect
			(start -0.5842 1.3335)
			(end 0.5842 -1.3335)
			(stroke
				(width 0)
				(type default)
			)
			(fill no)
			(layer "F.Fab")
		)
		(pad "1" smd custom
			(at 0 -0.762 270)
			(size 0.2159 0.2159)
			(layers "F.Cu" "F.Mask" "F.Paste")
			(net "P0V9_E")
			(options
				(clearance outline)
				(anchor circle)
			)
			(primitives
				(gr_poly
					(pts
						(arc
							(start -0.3302 -0.4318)
							(mid -0.402042 -0.402042)
							(end -0.4318 -0.3302)
						)
						(arc
							(start -0.4318 0.3302)
							(mid -0.402042 0.402042)
							(end -0.3302 0.4318)
						)
						(arc
							(start 0.3302 0.4318)
							(mid 0.402042 0.402042)
							(end 0.4318 0.3302)
						)
						(arc
							(start 0.4318 -0.3302)
							(mid 0.402042 -0.402042)
							(end 0.3302 -0.4318)
						)
					)
					(width 0)
					(fill yes)
				)
			)
		)
		(pad "2" smd custom
			(at 0 0.762 270)
			(size 0.2159 0.2159)
			(layers "F.Cu" "F.Mask" "F.Paste")
			(net "GB_VDDA")
			(options
				(clearance outline)
				(anchor circle)
			)
			(primitives
				(gr_poly
					(pts
						(arc
							(start -0.3302 -0.4318)
							(mid -0.402042 -0.402042)
							(end -0.4318 -0.3302)
						)
						(arc
							(start -0.4318 0.3302)
							(mid -0.402042 0.402042)
							(end -0.3302 0.4318)
						)
						(arc
							(start 0.3302 0.4318)
							(mid 0.402042 0.402042)
							(end 0.4318 0.3302)
						)
						(arc
							(start 0.4318 -0.3302)
							(mid 0.402042 -0.402042)
							(end 0.3302 -0.4318)
						)
					)
					(width 0)
					(fill yes)
				)
			)
		)
	)
	(footprint ""
		(layer "F.Cu")
		(at 287.401 -156.972 -90)
		(property "Reference" "R616"
			(at 0 0 270)
			(layer "F.SilkS")
			(hide yes)
			(effects
				(font
					(size 1.27 1.27)
				)
			)
		)
		(property "Value" "2K2R2J-2-GP"
			(at 0.064008 -3.993896 270)
			(unlocked yes)
			(layer "F.Fab")
			(hide yes)
			(effects
				(font
					(size 1.016 1.016)
					(thickness 0.1524)
				)
			)
		)
		(property "Device Type" "R402H16"
			(at 0.064008 -5.517896 270)
			(unlocked yes)
			(layer "F.Fab")
			(hide yes)
			(effects
				(font
					(size 1.016 1.016)
					(thickness 0.1524)
				)
			)
		)
		(duplicate_pad_numbers_are_jumpers no)
		(fp_line
			(start -0.508 -0.9398)
			(end -0.508 0.9398)
			(stroke
				(width 0.1524)
				(type default)
			)
			(layer "F.SilkS")
		)
		(fp_line
			(start 0.508 -0.9398)
			(end -0.508 -0.9398)
			(stroke
				(width 0.1524)
				(type default)
			)
			(layer "F.SilkS")
		)
		(fp_rect
			(start -0.508 0.9398)
			(end 0.508 -0.9398)
			(stroke
				(width 0)
				(type default)
			)
			(fill no)
			(layer "F.CrtYd")
		)
		(fp_rect
			(start -0.508 0.9398)
			(end 0.508 -0.9398)
			(stroke
				(width 0)
				(type default)
			)
			(fill no)
			(layer "F.Fab")
		)
		(pad "1" smd custom
			(at 0 -0.4445 270)
			(size 0.1397 0.1397)
			(layers "F.Cu" "F.Mask" "F.Paste")
			(net "CPU_BMC_UART_TX")
			(options
				(clearance outline)
				(anchor circle)
			)
			(primitives
				(gr_poly
					(pts
						(arc
							(start -0.1778 -0.2794)
							(mid -0.249642 -0.249642)
							(end -0.2794 -0.1778)
						)
						(arc
							(start -0.2794 0.1778)
							(mid -0.249642 0.249642)
							(end -0.1778 0.2794)
						)
						(arc
							(start 0.1778 0.2794)
							(mid 0.249642 0.249642)
							(end 0.2794 0.1778)
						)
						(arc
							(start 0.2794 -0.1778)
							(mid 0.249642 -0.249642)
							(end 0.1778 -0.2794)
						)
					)
					(width 0)
					(fill yes)
				)
			)
		)
		(pad "2" smd custom
			(at 0 0.4445 270)
			(size 0.1397 0.1397)
			(layers "F.Cu" "F.Mask" "F.Paste")
			(net "GND")
			(options
				(clearance outline)
				(anchor circle)
			)
			(primitives
				(gr_poly
					(pts
						(arc
							(start -0.1778 -0.2794)
							(mid -0.249642 -0.249642)
							(end -0.2794 -0.1778)
						)
						(arc
							(start -0.2794 0.1778)
							(mid -0.249642 0.249642)
							(end -0.1778 0.2794)
						)
						(arc
							(start 0.1778 0.2794)
							(mid 0.249642 0.249642)
							(end 0.2794 0.1778)
						)
						(arc
							(start 0.2794 -0.1778)
							(mid 0.249642 -0.249642)
							(end 0.1778 -0.2794)
						)
					)
					(width 0)
					(fill yes)
				)
			)
		)
	)
	(footprint ""
		(layer "F.Cu")
		(at 110.236 -62.103)
		(property "Reference" "STP60"
			(at 0 0 0)
			(layer "F.SilkS")
			(hide yes)
			(effects
				(font
					(size 1.27 1.27)
				)
			)
		)
		(property "Value" "TPAD28"
			(at 0.0127 -1.8034 0)
			(unlocked yes)
			(layer "F.Fab")
			(hide yes)
			(effects
				(font
					(size 1.016 1.016)
					(thickness 0.1524)
				)
			)
		)
		(property "Device Type" "TPAD28"
			(at 0.0127 -3.3274 0)
			(unlocked yes)
			(layer "F.Fab")
			(hide yes)
			(effects
				(font
					(size 1.016 1.016)
					(thickness 0.1524)
				)
			)
		)
		(duplicate_pad_numbers_are_jumpers no)
		(fp_poly
			(pts
				(arc
					(start 0.3556 0)
					(mid -0.3556 0)
					(end 0.3556 0)
				)
			)
			(stroke
				(width 0)
				(type default)
			)
			(fill no)
			(layer "F.CrtYd")
		)
		(fp_poly
			(pts
				(arc
					(start 0.6096 0)
					(mid -0.6096 0)
					(end 0.6096 0)
				)
			)
			(stroke
				(width 0)
				(type default)
			)
			(fill no)
			(layer "F.Fab")
		)
		(pad "1" smd circle
			(at 0 0)
			(size 0.7112 0.7112)
			(layers "F.Cu" "F.Mask" "F.Paste")
			(net "JTAG_IOC_TMS")
		)
	)
	(footprint ""
		(layer "F.Cu")
		(at 171.46397 -67.183 180)
		(property "Reference" "C295"
			(at 0 0 180)
			(layer "F.SilkS")
			(hide yes)
			(effects
				(font
					(size 1.27 1.27)
				)
			)
		)
		(property "Value" "SCD1U25V2KX-2-GP"
			(at 1.1811 -2.7051 180)
			(unlocked yes)
			(layer "F.Fab")
			(hide yes)
			(effects
				(font
					(size 1.016 1.016)
					(thickness 0.1524)
				)
			)
		)
		(property "Device Type" "C402H22"
			(at 1.1811 -4.2291 180)
			(unlocked yes)
			(layer "F.Fab")
			(hide yes)
			(effects
				(font
					(size 1.016 1.016)
					(thickness 0.1524)
				)
			)
		)
		(duplicate_pad_numbers_are_jumpers no)
		(fp_rect
			(start -0.4318 0.9525)
			(end 0.4318 -0.9525)
			(stroke
				(width 0)
				(type default)
			)
			(fill no)
			(layer "F.CrtYd")
		)
		(fp_rect
			(start -0.4318 0.9525)
			(end 0.4318 -0.9525)
			(stroke
				(width 0)
				(type default)
			)
			(fill no)
			(layer "F.Fab")
		)
		(pad "1" smd custom
			(at 0 -0.4445 180)
			(size 0.1524 0.1524)
			(layers "F.Cu" "F.Mask" "F.Paste")
			(net "GND")
			(options
				(clearance outline)
				(anchor circle)
			)
			(primitives
				(gr_poly
					(pts
						(arc
							(start 0.3048 -0.2032)
							(mid 0.275042 -0.275042)
							(end 0.2032 -0.3048)
						)
						(arc
							(start -0.2032 -0.3048)
							(mid -0.275042 -0.275042)
							(end -0.3048 -0.2032)
						)
						(arc
							(start -0.3048 0.2032)
							(mid -0.275042 0.275042)
							(end -0.2032 0.3048)
						)
						(arc
							(start 0.2032 0.3048)
							(mid 0.275042 0.275042)
							(end 0.3048 0.2032)
						)
					)
					(width 0)
					(fill yes)
				)
			)
		)
		(pad "2" smd custom
			(at 0 0.4445 180)
			(size 0.1524 0.1524)
			(layers "F.Cu" "F.Mask" "F.Paste")
			(net "TP_MSB_B47_CPU_GBE_TX_N")
			(options
				(clearance outline)
				(anchor circle)
			)
			(primitives
				(gr_poly
					(pts
						(arc
							(start 0.3048 -0.2032)
							(mid 0.275042 -0.275042)
							(end 0.2032 -0.3048)
						)
						(arc
							(start -0.2032 -0.3048)
							(mid -0.275042 -0.275042)
							(end -0.3048 -0.2032)
						)
						(arc
							(start -0.3048 0.2032)
							(mid -0.275042 0.275042)
							(end -0.2032 0.3048)
						)
						(arc
							(start 0.2032 0.3048)
							(mid 0.275042 0.275042)
							(end 0.3048 0.2032)
						)
					)
					(width 0)
					(fill yes)
				)
			)
		)
	)
	(footprint ""
		(layer "F.Cu")
		(at 62.357 -216.281 90)
		(property "Reference" "C7272"
			(at 0 0 90)
			(layer "F.SilkS")
			(hide yes)
			(effects
				(font
					(size 1.27 1.27)
				)
			)
		)
		(property "Value" "SCD1U16V2KX-3GP"
			(at 1.1811 -2.7051 90)
			(unlocked yes)
			(layer "F.Fab")
			(hide yes)
			(effects
				(font
					(size 1.016 1.016)
					(thickness 0.1524)
				)
			)
		)
		(property "Device Type" "C402H22"
			(at 1.1811 -4.2291 90)
			(unlocked yes)
			(layer "F.Fab")
			(hide yes)
			(effects
				(font
					(size 1.016 1.016)
					(thickness 0.1524)
				)
			)
		)
		(duplicate_pad_numbers_are_jumpers no)
		(fp_rect
			(start -0.4318 0.9525)
			(end 0.4318 -0.9525)
			(stroke
				(width 0)
				(type default)
			)
			(fill no)
			(layer "F.CrtYd")
		)
		(fp_rect
			(start -0.4318 0.9525)
			(end 0.4318 -0.9525)
			(stroke
				(width 0)
				(type default)
			)
			(fill no)
			(layer "F.Fab")
		)
		(pad "1" smd custom
			(at 0 -0.4445 90)
			(size 0.1524 0.1524)
			(layers "F.Cu" "F.Mask" "F.Paste")
			(net "MB0_CM_VOUT_R")
			(options
				(clearance outline)
				(anchor circle)
			)
			(primitives
				(gr_poly
					(pts
						(arc
							(start 0.3048 -0.2032)
							(mid 0.275042 -0.275042)
							(end 0.2032 -0.3048)
						)
						(arc
							(start -0.2032 -0.3048)
							(mid -0.275042 -0.275042)
							(end -0.3048 -0.2032)
						)
						(arc
							(start -0.3048 0.2032)
							(mid -0.275042 0.275042)
							(end -0.2032 0.3048)
						)
						(arc
							(start 0.2032 0.3048)
							(mid 0.275042 0.275042)
							(end 0.3048 0.2032)
						)
					)
					(width 0)
					(fill yes)
				)
			)
		)
		(pad "2" smd custom
			(at 0 0.4445 90)
			(size 0.1524 0.1524)
			(layers "F.Cu" "F.Mask" "F.Paste")
			(net "AGND_CURRENT_MON")
			(options
				(clearance outline)
				(anchor circle)
			)
			(primitives
				(gr_poly
					(pts
						(arc
							(start 0.3048 -0.2032)
							(mid 0.275042 -0.275042)
							(end 0.2032 -0.3048)
						)
						(arc
							(start -0.2032 -0.3048)
							(mid -0.275042 -0.275042)
							(end -0.3048 -0.2032)
						)
						(arc
							(start -0.3048 0.2032)
							(mid -0.275042 0.275042)
							(end -0.2032 0.3048)
						)
						(arc
							(start 0.2032 0.3048)
							(mid 0.275042 0.275042)
							(end 0.3048 0.2032)
						)
					)
					(width 0)
					(fill yes)
				)
			)
		)
	)
	(footprint ""
		(layer "F.Cu")
		(at 83.420966 -80.391)
		(property "Reference" "SC1194"
			(at 0 0 0)
			(layer "F.SilkS")
			(hide yes)
			(effects
				(font
					(size 1.27 1.27)
				)
			)
		)
		(property "Value" "SC22U6D3V5MX-2GP"
			(at -0.0762 -6.1214 0)
			(unlocked yes)
			(layer "F.Fab")
			(hide yes)
			(effects
				(font
					(size 1.016 1.016)
					(thickness 0.1524)
				)
			)
		)
		(property "Device Type" "C805H58"
			(at -0.0762 -8.1534 0)
			(unlocked yes)
			(layer "F.Fab")
			(hide yes)
			(effects
				(font
					(size 1.016 1.016)
					(thickness 0.1524)
				)
			)
		)
		(duplicate_pad_numbers_are_jumpers no)
		(fp_line
			(start 0.635 0)
			(end -0.635 0)
			(stroke
				(width 0.508)
				(type default)
			)
			(layer "F.SilkS")
		)
		(fp_rect
			(start -0.9652 1.778)
			(end 0.9652 -1.778)
			(stroke
				(width 0)
				(type default)
			)
			(fill no)
			(layer "F.CrtYd")
		)
		(fp_poly
			(pts
				(xy -0.9652 -1.778) (xy 0.9652 -1.778) (xy 0.9652 1.778) (xy -0.9652 1.778)
			)
			(stroke
				(width 0)
				(type default)
			)
			(fill no)
			(layer "F.Fab")
		)
		(pad "1" smd rect
			(at 0 -0.9652)
			(size 1.397 1.143)
			(layers "F.Cu" "F.Mask" "F.Paste")
			(net "XTAL_VDDA09")
		)
		(pad "2" smd rect
			(at 0 0.9652)
			(size 1.397 1.143)
			(layers "F.Cu" "F.Mask" "F.Paste")
			(net "GND")
		)
	)
	(footprint ""
		(layer "F.Cu")
		(at 110.217966 -65.8876)
		(property "Reference" "SR661"
			(at 0 0 0)
			(layer "F.SilkS")
			(hide yes)
			(effects
				(font
					(size 1.27 1.27)
				)
			)
		)
		(property "Value" "10KR2F-2-GP"
			(at 0.064008 -3.993896 0)
			(unlocked yes)
			(layer "F.Fab")
			(hide yes)
			(effects
				(font
					(size 1.016 1.016)
					(thickness 0.1524)
				)
			)
		)
		(property "Device Type" "R402H16"
			(at 0.064008 -5.517896 0)
			(unlocked yes)
			(layer "F.Fab")
			(hide yes)
			(effects
				(font
					(size 1.016 1.016)
					(thickness 0.1524)
				)
			)
		)
		(duplicate_pad_numbers_are_jumpers no)
		(fp_line
			(start -0.508 -0.9398)
			(end -0.508 0.9398)
			(stroke
				(width 0.1524)
				(type default)
			)
			(layer "F.SilkS")
		)
		(fp_line
			(start 0.508 -0.9398)
			(end -0.508 -0.9398)
			(stroke
				(width 0.1524)
				(type default)
			)
			(layer "F.SilkS")
		)
		(fp_rect
			(start -0.508 0.9398)
			(end 0.508 -0.9398)
			(stroke
				(width 0)
				(type default)
			)
			(fill no)
			(layer "F.CrtYd")
		)
		(fp_rect
			(start -0.508 0.9398)
			(end 0.508 -0.9398)
			(stroke
				(width 0)
				(type default)
			)
			(fill no)
			(layer "F.Fab")
		)
		(pad "1" smd custom
			(at 0 -0.4445)
			(size 0.1397 0.1397)
			(layers "F.Cu" "F.Mask" "F.Paste")
			(net "P1V8_C")
			(options
				(clearance outline)
				(anchor circle)
			)
			(primitives
				(gr_poly
					(pts
						(arc
							(start -0.1778 -0.2794)
							(mid -0.249642 -0.249642)
							(end -0.2794 -0.1778)
						)
						(arc
							(start -0.2794 0.1778)
							(mid -0.249642 0.249642)
							(end -0.1778 0.2794)
						)
						(arc
							(start 0.1778 0.2794)
							(mid 0.249642 0.249642)
							(end 0.2794 0.1778)
						)
						(arc
							(start 0.2794 -0.1778)
							(mid 0.249642 -0.249642)
							(end 0.1778 -0.2794)
						)
					)
					(width 0)
					(fill yes)
				)
			)
		)
		(pad "2" smd custom
			(at 0 0.4445)
			(size 0.1397 0.1397)
			(layers "F.Cu" "F.Mask" "F.Paste")
			(net "LSI_JTAG_EN_N")
			(options
				(clearance outline)
				(anchor circle)
			)
			(primitives
				(gr_poly
					(pts
						(arc
							(start -0.1778 -0.2794)
							(mid -0.249642 -0.249642)
							(end -0.2794 -0.1778)
						)
						(arc
							(start -0.2794 0.1778)
							(mid -0.249642 0.249642)
							(end -0.1778 0.2794)
						)
						(arc
							(start 0.1778 0.2794)
							(mid 0.249642 0.249642)
							(end 0.2794 0.1778)
						)
						(arc
							(start 0.2794 -0.1778)
							(mid 0.249642 -0.249642)
							(end 0.1778 -0.2794)
						)
					)
					(width 0)
					(fill yes)
				)
			)
		)
	)
	(footprint ""
		(layer "F.Cu")
		(at 335.915 -83.947 180)
		(property "Reference" "R296"
			(at 0 0 180)
			(layer "F.SilkS")
			(hide yes)
			(effects
				(font
					(size 1.27 1.27)
				)
			)
		)
		(property "Value" "0R0402-PAD-1-GP"
			(at 0.064008 -3.993896 180)
			(unlocked yes)
			(layer "F.Fab")
			(hide yes)
			(effects
				(font
					(size 1.016 1.016)
					(thickness 0.1524)
				)
			)
		)
		(property "Device Type" "0R0402-PAD"
			(at 0.064008 -5.517896 180)
			(unlocked yes)
			(layer "F.Fab")
			(hide yes)
			(effects
				(font
					(size 1.016 1.016)
					(thickness 0.1524)
				)
			)
		)
		(duplicate_pad_numbers_are_jumpers no)
		(fp_line
			(start 0.508 -0.9398)
			(end -0.508 -0.9398)
			(stroke
				(width 0.1524)
				(type default)
			)
			(layer "F.SilkS")
		)
		(fp_line
			(start -0.508 -0.9398)
			(end -0.508 0.9398)
			(stroke
				(width 0.1524)
				(type default)
			)
			(layer "F.SilkS")
		)
		(fp_rect
			(start -0.508 0.9398)
			(end 0.508 -0.9398)
			(stroke
				(width 0)
				(type default)
			)
			(fill no)
			(layer "F.CrtYd")
		)
		(fp_rect
			(start -0.508 0.9398)
			(end 0.508 -0.9398)
			(stroke
				(width 0)
				(type default)
			)
			(fill no)
			(layer "F.Fab")
		)
		(pad "1" smd custom
			(at 0 -0.4445 180)
			(size 0.1397 0.1397)
			(layers "F.Cu" "F.Mask" "F.Paste")
			(net "FLA_CS_R")
			(options
				(clearance outline)
				(anchor circle)
			)
			(primitives
				(gr_poly
					(pts
						(xy -0.2794 0.3683)
						(arc
							(start -0.2794 -0.2667)
							(mid -0.249642 -0.338542)
							(end -0.1778 -0.3683)
						)
						(arc
							(start 0.1778 -0.3683)
							(mid 0.249642 -0.338542)
							(end 0.2794 -0.2667)
						)
						(xy 0.2794 0.3683)
					)
					(width 0)
					(fill yes)
				)
			)
		)
		(pad "2" smd custom
			(at 0 0.4445 180)
			(size 0.1397 0.1397)
			(layers "F.Cu" "F.Mask" "F.Paste")
			(net "FLA_CS")
			(options
				(clearance outline)
				(anchor circle)
			)
			(primitives
				(gr_poly
					(pts
						(arc
							(start -0.1778 0.3683)
							(mid -0.249642 0.338542)
							(end -0.2794 0.2667)
						)
						(xy -0.2794 -0.3683) (xy 0.2794 -0.3683)
						(arc
							(start 0.2794 0.2667)
							(mid 0.249642 0.338542)
							(end 0.1778 0.3683)
						)
					)
					(width 0)
					(fill yes)
				)
			)
		)
	)
)
